(kicad_pcb
	(version 20260206)
	(generator "pcbnew")
	(generator_version "10.0")
	(general
		(thickness 1.6)
		(legacy_teardrops no)
	)
	(paper "A4")
	(title_block
		(title "Bryce Canyon_SCC_16316-1_OCP.brd")
		(comment 1 "Bryce Canyon / footprints 95-102 of 1561")
	)
	(layers
		(0 "F.Cu" signal "TOP")
		(4 "In1.Cu" signal "L2GND")
		(6 "In2.Cu" signal "L3")
		(8 "In3.Cu" signal "L4VCC")
		(10 "In4.Cu" signal "L5VCC")
		(12 "In5.Cu" signal "L6")
		(14 "In6.Cu" signal "L7GND")
		(2 "B.Cu" signal "BOTTOM")
		(9 "F.Adhes" user "F.Adhesive")
		(11 "B.Adhes" user "B.Adhesive")
		(13 "F.Paste" user "Package Geometry/Pastemask Top")
		(15 "B.Paste" user "Package Geometry/Pastemask Bottom")
		(5 "F.SilkS" user "Ref Des/Silkscreen Top")
		(7 "B.SilkS" user "Ref Des/Silkscreen Bottom")
		(1 "F.Mask" user "Board Geometry/Soldermask Top")
		(3 "B.Mask" user "Board Geometry/Soldermask Bottom")
		(17 "Dwgs.User" user "User.Drawings")
		(19 "Cmts.User" user "User.Comments")
		(21 "Eco1.User" user "User.Eco1")
		(23 "Eco2.User" user "User.Eco2")
		(25 "Edge.Cuts" user "Board Geometry/Outline")
		(27 "Margin" user)
		(31 "F.CrtYd" user "Package Geometry/Place Bound Top")
		(29 "B.CrtYd" user "Package Geometry/Place Bound Bottom")
		(35 "F.Fab" user "Ref Des/Assembly Top")
		(33 "B.Fab" user "Ref Des/Assembly Bottom")
	)
	(footprint ""
		(layer "F.Cu")
		(at 166.125398 -23.611332 90)
		(property "Reference" "VIA1"
			(at 0 0 90)
			(layer "F.SilkS")
			(hide yes)
			(effects
				(font
					(size 1.27 1.27)
				)
			)
		)
		(property "Value" "85OHM-8L-1D6MM-L16L18-GP"
			(at 4.064 0.6096 90)
			(unlocked yes)
			(layer "F.Fab")
			(hide yes)
			(effects
				(font
					(size 1.016 1.016)
					(thickness 0.1524)
				)
			)
		)
		(property "Device Type" "VIA-PCIE-4P-368076"
			(at 4.064 -0.9144 90)
			(unlocked yes)
			(layer "F.Fab")
			(hide yes)
			(effects
				(font
					(size 1.016 1.016)
					(thickness 0.1524)
				)
			)
		)
		(duplicate_pad_numbers_are_jumpers no)
		(fp_rect
			(start -1.8415 0.381)
			(end 1.8415 -0.381)
			(stroke
				(width 0)
				(type default)
			)
			(fill no)
			(layer "F.CrtYd")
		)
		(fp_rect
			(start -1.8415 0.381)
			(end 1.8415 -0.381)
			(stroke
				(width 0)
				(type default)
			)
			(fill no)
			(layer "F.Fab")
		)
		(pad "1" thru_hole circle
			(at -1.4605 0 90)
			(size 0.508 0.508)
			(drill 0.254)
			(layers "*.Cu" "*.Mask")
			(remove_unused_layers no)
			(net "GND")
			(clearance 0.127)
			(thermal_gap 0.127)
		)
		(pad "2" thru_hole circle
			(at -0.4445 0 90)
			(size 0.508 0.508)
			(drill 0.254)
			(layers "*.Cu" "*.Mask")
			(remove_unused_layers no)
			(net "PCIE_COMP_TO_SCC_0_DP")
			(clearance 0.127)
			(thermal_gap 0.127)
		)
		(pad "3" thru_hole circle
			(at 0.4445 0 90)
			(size 0.508 0.508)
			(drill 0.254)
			(layers "*.Cu" "*.Mask")
			(remove_unused_layers no)
			(net "PCIE_COMP_TO_SCC_0_DN")
			(clearance 0.127)
			(thermal_gap 0.127)
		)
		(pad "4" thru_hole circle
			(at 1.4605 0 90)
			(size 0.508 0.508)
			(drill 0.254)
			(layers "*.Cu" "*.Mask")
			(remove_unused_layers no)
			(net "GND")
			(clearance 0.127)
			(thermal_gap 0.127)
		)
	)
	(footprint ""
		(layer "F.Cu")
		(at 157.166818 -96.239076 -90)
		(property "Reference" "R315"
			(at 0 0 270)
			(layer "F.SilkS")
			(hide yes)
			(effects
				(font
					(size 1.27 1.27)
				)
			)
		)
		(property "Value" "0R2J-2-GP"
			(at 0.064008 -3.993896 270)
			(unlocked yes)
			(layer "F.Fab")
			(hide yes)
			(effects
				(font
					(size 1.016 1.016)
					(thickness 0.1524)
				)
			)
		)
		(property "Device Type" "R402H16"
			(at 0.064008 -5.517896 270)
			(unlocked yes)
			(layer "F.Fab")
			(hide yes)
			(effects
				(font
					(size 1.016 1.016)
					(thickness 0.1524)
				)
			)
		)
		(duplicate_pad_numbers_are_jumpers no)
		(fp_line
			(start -0.508 -0.9398)
			(end -0.508 0.9398)
			(stroke
				(width 0.1524)
				(type default)
			)
			(layer "F.SilkS")
		)
		(fp_line
			(start 0.508 -0.9398)
			(end -0.508 -0.9398)
			(stroke
				(width 0.1524)
				(type default)
			)
			(layer "F.SilkS")
		)
		(fp_rect
			(start -0.508 0.9398)
			(end 0.508 -0.9398)
			(stroke
				(width 0)
				(type default)
			)
			(fill no)
			(layer "F.CrtYd")
		)
		(fp_rect
			(start -0.508 0.9398)
			(end 0.508 -0.9398)
			(stroke
				(width 0)
				(type default)
			)
			(fill no)
			(layer "F.Fab")
		)
		(pad "1" smd custom
			(at 0 -0.4445 270)
			(size 0.1397 0.1397)
			(layers "F.Cu" "F.Mask" "F.Paste")
			(net "UART_EXP_RX")
			(options
				(clearance outline)
				(anchor circle)
			)
			(primitives
				(gr_poly
					(pts
						(arc
							(start -0.1778 -0.2794)
							(mid -0.249642 -0.249642)
							(end -0.2794 -0.1778)
						)
						(arc
							(start -0.2794 0.1778)
							(mid -0.249642 0.249642)
							(end -0.1778 0.2794)
						)
						(arc
							(start 0.1778 0.2794)
							(mid 0.249642 0.249642)
							(end 0.2794 0.1778)
						)
						(arc
							(start 0.2794 -0.1778)
							(mid 0.249642 -0.249642)
							(end 0.1778 -0.2794)
						)
					)
					(width 0)
					(fill yes)
				)
			)
		)
		(pad "2" smd custom
			(at 0 0.4445 270)
			(size 0.1397 0.1397)
			(layers "F.Cu" "F.Mask" "F.Paste")
			(net "EXP_SMART_RX_R")
			(options
				(clearance outline)
				(anchor circle)
			)
			(primitives
				(gr_poly
					(pts
						(arc
							(start -0.1778 -0.2794)
							(mid -0.249642 -0.249642)
							(end -0.2794 -0.1778)
						)
						(arc
							(start -0.2794 0.1778)
							(mid -0.249642 0.249642)
							(end -0.1778 0.2794)
						)
						(arc
							(start 0.1778 0.2794)
							(mid 0.249642 0.249642)
							(end 0.2794 0.1778)
						)
						(arc
							(start 0.2794 -0.1778)
							(mid 0.249642 -0.249642)
							(end 0.1778 -0.2794)
						)
					)
					(width 0)
					(fill yes)
				)
			)
		)
	)
	(footprint ""
		(layer "F.Cu")
		(at 121.92 -93.1672 90)
		(property "Reference" "R308"
			(at 0 0 90)
			(layer "F.SilkS")
			(hide yes)
			(effects
				(font
					(size 1.27 1.27)
				)
			)
		)
		(property "Value" "10KR2F-2-GP"
			(at 0.064008 -3.993896 90)
			(unlocked yes)
			(layer "F.Fab")
			(hide yes)
			(effects
				(font
					(size 1.016 1.016)
					(thickness 0.1524)
				)
			)
		)
		(property "Device Type" "R402H16"
			(at 0.064008 -5.517896 90)
			(unlocked yes)
			(layer "F.Fab")
			(hide yes)
			(effects
				(font
					(size 1.016 1.016)
					(thickness 0.1524)
				)
			)
		)
		(duplicate_pad_numbers_are_jumpers no)
		(fp_line
			(start 0.508 -0.9398)
			(end -0.508 -0.9398)
			(stroke
				(width 0.1524)
				(type default)
			)
			(layer "F.SilkS")
		)
		(fp_line
			(start -0.508 -0.9398)
			(end -0.508 0.9398)
			(stroke
				(width 0.1524)
				(type default)
			)
			(layer "F.SilkS")
		)
		(fp_rect
			(start -0.508 0.9398)
			(end 0.508 -0.9398)
			(stroke
				(width 0)
				(type default)
			)
			(fill no)
			(layer "F.CrtYd")
		)
		(fp_rect
			(start -0.508 0.9398)
			(end 0.508 -0.9398)
			(stroke
				(width 0)
				(type default)
			)
			(fill no)
			(layer "F.Fab")
		)
		(pad "1" smd custom
			(at 0 -0.4445 90)
			(size 0.1397 0.1397)
			(layers "F.Cu" "F.Mask" "F.Paste")
			(net "BMC_SPARE_1_LS")
			(options
				(clearance outline)
				(anchor circle)
			)
			(primitives
				(gr_poly
					(pts
						(arc
							(start -0.1778 -0.2794)
							(mid -0.249642 -0.249642)
							(end -0.2794 -0.1778)
						)
						(arc
							(start -0.2794 0.1778)
							(mid -0.249642 0.249642)
							(end -0.1778 0.2794)
						)
						(arc
							(start 0.1778 0.2794)
							(mid 0.249642 0.249642)
							(end 0.2794 0.1778)
						)
						(arc
							(start 0.2794 -0.1778)
							(mid 0.249642 -0.249642)
							(end 0.1778 -0.2794)
						)
					)
					(width 0)
					(fill yes)
				)
			)
		)
		(pad "2" smd custom
			(at 0 0.4445 90)
			(size 0.1397 0.1397)
			(layers "F.Cu" "F.Mask" "F.Paste")
			(net "GND")
			(options
				(clearance outline)
				(anchor circle)
			)
			(primitives
				(gr_poly
					(pts
						(arc
							(start -0.1778 -0.2794)
							(mid -0.249642 -0.249642)
							(end -0.2794 -0.1778)
						)
						(arc
							(start -0.2794 0.1778)
							(mid -0.249642 0.249642)
							(end -0.1778 0.2794)
						)
						(arc
							(start 0.1778 0.2794)
							(mid 0.249642 0.249642)
							(end 0.2794 0.1778)
						)
						(arc
							(start 0.2794 -0.1778)
							(mid 0.249642 -0.249642)
							(end 0.1778 -0.2794)
						)
					)
					(width 0)
					(fill yes)
				)
			)
		)
	)
	(footprint ""
		(layer "F.Cu")
		(at 158.81858 -99.04476 90)
		(property "Reference" "C507"
			(at 0 0 90)
			(layer "F.SilkS")
			(hide yes)
			(effects
				(font
					(size 1.27 1.27)
				)
			)
		)
		(property "Value" "SCD1U16V2KX-3GP"
			(at 1.1811 -2.7051 90)
			(unlocked yes)
			(layer "F.Fab")
			(hide yes)
			(effects
				(font
					(size 1.016 1.016)
					(thickness 0.1524)
				)
			)
		)
		(property "Device Type" "C402H22"
			(at 1.1811 -4.2291 90)
			(unlocked yes)
			(layer "F.Fab")
			(hide yes)
			(effects
				(font
					(size 1.016 1.016)
					(thickness 0.1524)
				)
			)
		)
		(duplicate_pad_numbers_are_jumpers no)
		(fp_rect
			(start -0.4318 0.9525)
			(end 0.4318 -0.9525)
			(stroke
				(width 0)
				(type default)
			)
			(fill no)
			(layer "F.CrtYd")
		)
		(fp_rect
			(start -0.4318 0.9525)
			(end 0.4318 -0.9525)
			(stroke
				(width 0)
				(type default)
			)
			(fill no)
			(layer "F.Fab")
		)
		(pad "1" smd custom
			(at 0 -0.4445 90)
			(size 0.1524 0.1524)
			(layers "F.Cu" "F.Mask" "F.Paste")
			(net "P3V3")
			(options
				(clearance outline)
				(anchor circle)
			)
			(primitives
				(gr_poly
					(pts
						(arc
							(start 0.3048 -0.2032)
							(mid 0.275042 -0.275042)
							(end 0.2032 -0.3048)
						)
						(arc
							(start -0.2032 -0.3048)
							(mid -0.275042 -0.275042)
							(end -0.3048 -0.2032)
						)
						(arc
							(start -0.3048 0.2032)
							(mid -0.275042 0.275042)
							(end -0.2032 0.3048)
						)
						(arc
							(start 0.2032 0.3048)
							(mid 0.275042 0.275042)
							(end 0.3048 0.2032)
						)
					)
					(width 0)
					(fill yes)
				)
			)
		)
		(pad "2" smd custom
			(at 0 0.4445 90)
			(size 0.1524 0.1524)
			(layers "F.Cu" "F.Mask" "F.Paste")
			(net "GND")
			(options
				(clearance outline)
				(anchor circle)
			)
			(primitives
				(gr_poly
					(pts
						(arc
							(start 0.3048 -0.2032)
							(mid 0.275042 -0.275042)
							(end 0.2032 -0.3048)
						)
						(arc
							(start -0.2032 -0.3048)
							(mid -0.275042 -0.275042)
							(end -0.3048 -0.2032)
						)
						(arc
							(start -0.3048 0.2032)
							(mid -0.275042 0.275042)
							(end -0.2032 0.3048)
						)
						(arc
							(start 0.2032 0.3048)
							(mid 0.275042 0.275042)
							(end 0.3048 0.2032)
						)
					)
					(width 0)
					(fill yes)
				)
			)
		)
	)
	(footprint ""
		(layer "F.Cu")
		(at 191.0334 -40.6527 -90)
		(property "Reference" "R256"
			(at 0 0 270)
			(layer "F.SilkS")
			(hide yes)
			(effects
				(font
					(size 1.27 1.27)
				)
			)
		)
		(property "Value" "10KR2F-2-GP"
			(at 0.064008 -3.993896 270)
			(unlocked yes)
			(layer "F.Fab")
			(hide yes)
			(effects
				(font
					(size 1.016 1.016)
					(thickness 0.1524)
				)
			)
		)
		(property "Device Type" "R402H16"
			(at 0.064008 -5.517896 270)
			(unlocked yes)
			(layer "F.Fab")
			(hide yes)
			(effects
				(font
					(size 1.016 1.016)
					(thickness 0.1524)
				)
			)
		)
		(duplicate_pad_numbers_are_jumpers no)
		(fp_line
			(start -0.508 -0.9398)
			(end -0.508 0.9398)
			(stroke
				(width 0.1524)
				(type default)
			)
			(layer "F.SilkS")
		)
		(fp_line
			(start 0.508 -0.9398)
			(end -0.508 -0.9398)
			(stroke
				(width 0.1524)
				(type default)
			)
			(layer "F.SilkS")
		)
		(fp_rect
			(start -0.508 0.9398)
			(end 0.508 -0.9398)
			(stroke
				(width 0)
				(type default)
			)
			(fill no)
			(layer "F.CrtYd")
		)
		(fp_rect
			(start -0.508 0.9398)
			(end 0.508 -0.9398)
			(stroke
				(width 0)
				(type default)
			)
			(fill no)
			(layer "F.Fab")
		)
		(pad "1" smd custom
			(at 0 -0.4445 270)
			(size 0.1397 0.1397)
			(layers "F.Cu" "F.Mask" "F.Paste")
			(net "P1V8_C")
			(options
				(clearance outline)
				(anchor circle)
			)
			(primitives
				(gr_poly
					(pts
						(arc
							(start -0.1778 -0.2794)
							(mid -0.249642 -0.249642)
							(end -0.2794 -0.1778)
						)
						(arc
							(start -0.2794 0.1778)
							(mid -0.249642 0.249642)
							(end -0.1778 0.2794)
						)
						(arc
							(start 0.1778 0.2794)
							(mid 0.249642 0.249642)
							(end 0.2794 0.1778)
						)
						(arc
							(start 0.2794 -0.1778)
							(mid 0.249642 -0.249642)
							(end 0.1778 -0.2794)
						)
					)
					(width 0)
					(fill yes)
				)
			)
		)
		(pad "2" smd custom
			(at 0 0.4445 270)
			(size 0.1397 0.1397)
			(layers "F.Cu" "F.Mask" "F.Paste")
			(net "SYS_CORE_TRI#")
			(options
				(clearance outline)
				(anchor circle)
			)
			(primitives
				(gr_poly
					(pts
						(arc
							(start -0.1778 -0.2794)
							(mid -0.249642 -0.249642)
							(end -0.2794 -0.1778)
						)
						(arc
							(start -0.2794 0.1778)
							(mid -0.249642 0.249642)
							(end -0.1778 0.2794)
						)
						(arc
							(start 0.1778 0.2794)
							(mid 0.249642 0.249642)
							(end 0.2794 0.1778)
						)
						(arc
							(start 0.2794 -0.1778)
							(mid 0.249642 -0.249642)
							(end 0.1778 -0.2794)
						)
					)
					(width 0)
					(fill yes)
				)
			)
		)
	)
	(footprint ""
		(layer "F.Cu")
		(at 173.2026 -82.4484)
		(property "Reference" "R284"
			(at 0 0 0)
			(layer "F.SilkS")
			(hide yes)
			(effects
				(font
					(size 1.27 1.27)
				)
			)
		)
		(property "Value" "D51R3F-2-GP"
			(at -0.0254 -2.5146 0)
			(unlocked yes)
			(layer "F.Fab")
			(hide yes)
			(effects
				(font
					(size 1.016 1.016)
					(thickness 0.1524)
				)
			)
		)
		(property "Device Type" "R603H22"
			(at -0.0254 -4.0386 0)
			(unlocked yes)
			(layer "F.Fab")
			(hide yes)
			(effects
				(font
					(size 1.016 1.016)
					(thickness 0.1524)
				)
			)
		)
		(duplicate_pad_numbers_are_jumpers no)
		(fp_line
			(start -0.4826 0)
			(end -0.2032 0)
			(stroke
				(width 0.2032)
				(type default)
			)
			(layer "F.SilkS")
		)
		(fp_line
			(start 0.2032 0)
			(end 0.4826 0)
			(stroke
				(width 0.2032)
				(type default)
			)
			(layer "F.SilkS")
		)
		(fp_rect
			(start -0.5842 1.3335)
			(end 0.5842 -1.3335)
			(stroke
				(width 0)
				(type default)
			)
			(fill no)
			(layer "F.CrtYd")
		)
		(fp_rect
			(start -0.5842 1.3335)
			(end 0.5842 -1.3335)
			(stroke
				(width 0)
				(type default)
			)
			(fill no)
			(layer "F.Fab")
		)
		(pad "1" smd custom
			(at 0 -0.762)
			(size 0.2159 0.2159)
			(layers "F.Cu" "F.Mask" "F.Paste")
			(net "P0V975")
			(options
				(clearance outline)
				(anchor circle)
			)
			(primitives
				(gr_poly
					(pts
						(arc
							(start -0.3302 -0.4318)
							(mid -0.402042 -0.402042)
							(end -0.4318 -0.3302)
						)
						(arc
							(start -0.4318 0.3302)
							(mid -0.402042 0.402042)
							(end -0.3302 0.4318)
						)
						(arc
							(start 0.3302 0.4318)
							(mid 0.402042 0.402042)
							(end 0.4318 0.3302)
						)
						(arc
							(start 0.4318 -0.3302)
							(mid 0.402042 -0.402042)
							(end 0.3302 -0.4318)
						)
					)
					(width 0)
					(fill yes)
				)
			)
		)
		(pad "2" smd custom
			(at 0 0.762)
			(size 0.2159 0.2159)
			(layers "F.Cu" "F.Mask" "F.Paste")
			(net "PCE_AVDD")
			(options
				(clearance outline)
				(anchor circle)
			)
			(primitives
				(gr_poly
					(pts
						(arc
							(start -0.3302 -0.4318)
							(mid -0.402042 -0.402042)
							(end -0.4318 -0.3302)
						)
						(arc
							(start -0.4318 0.3302)
							(mid -0.402042 0.402042)
							(end -0.3302 0.4318)
						)
						(arc
							(start 0.3302 0.4318)
							(mid 0.402042 0.402042)
							(end 0.4318 0.3302)
						)
						(arc
							(start 0.4318 -0.3302)
							(mid 0.402042 -0.402042)
							(end 0.3302 -0.4318)
						)
					)
					(width 0)
					(fill yes)
				)
			)
		)
	)
	(footprint ""
		(layer "F.Cu")
		(at 142.35176 -61.863986 -90)
		(property "Reference" "C35"
			(at 0 0 270)
			(layer "F.SilkS")
			(hide yes)
			(effects
				(font
					(size 1.27 1.27)
				)
			)
		)
		(property "Value" "SCD01U16V1KX-GP"
			(at -2.8321 -1.7399 270)
			(unlocked yes)
			(layer "F.Fab")
			(hide yes)
			(effects
				(font
					(size 1.016 1.016)
					(thickness 0.1524)
				)
			)
		)
		(property "Device Type" "C0201H13"
			(at -2.8321 -3.2639 270)
			(unlocked yes)
			(layer "F.Fab")
			(hide yes)
			(effects
				(font
					(size 1.016 1.016)
					(thickness 0.1524)
				)
			)
		)
		(duplicate_pad_numbers_are_jumpers no)
		(fp_rect
			(start -0.2794 0.6477)
			(end 0.2794 -0.6477)
			(stroke
				(width 0)
				(type default)
			)
			(fill no)
			(layer "F.CrtYd")
		)
		(fp_rect
			(start -0.2794 0.6477)
			(end 0.2794 -0.6477)
			(stroke
				(width 0)
				(type default)
			)
			(fill no)
			(layer "F.Fab")
		)
		(pad "1" smd custom
			(at 0 -0.2794 270)
			(size 0.0762 0.0762)
			(layers "F.Cu" "F.Mask" "F.Paste")
			(net "PHY_IOC_TO_SCC_46_DP")
			(options
				(clearance outline)
				(anchor circle)
			)
			(primitives
				(gr_poly
					(pts
						(arc
							(start 0.1524 -0.127)
							(mid 0.137521 -0.162921)
							(end 0.1016 -0.1778)
						)
						(arc
							(start -0.1016 -0.1778)
							(mid -0.137521 -0.162921)
							(end -0.1524 -0.127)
						)
						(arc
							(start -0.1524 0.127)
							(mid -0.137521 0.162921)
							(end -0.1016 0.1778)
						)
						(arc
							(start 0.1016 0.1778)
							(mid 0.137521 0.162921)
							(end 0.1524 0.127)
						)
					)
					(width 0)
					(fill yes)
				)
			)
		)
		(pad "2" smd custom
			(at 0 0.2794 270)
			(size 0.0762 0.0762)
			(layers "F.Cu" "F.Mask" "F.Paste")
			(net "PHY_IOC_TO_SCC_C_46_DP")
			(options
				(clearance outline)
				(anchor circle)
			)
			(primitives
				(gr_poly
					(pts
						(arc
							(start 0.1524 -0.127)
							(mid 0.137521 -0.162921)
							(end 0.1016 -0.1778)
						)
						(arc
							(start -0.1016 -0.1778)
							(mid -0.137521 -0.162921)
							(end -0.1524 -0.127)
						)
						(arc
							(start -0.1524 0.127)
							(mid -0.137521 0.162921)
							(end -0.1016 0.1778)
						)
						(arc
							(start 0.1016 0.1778)
							(mid 0.137521 0.162921)
							(end 0.1524 0.127)
						)
					)
					(width 0)
					(fill yes)
				)
			)
		)
	)
	(footprint ""
		(layer "F.Cu")
		(at 148.069554 -35.727386 102)
		(property "Reference" "C329"
			(at 0 0 102)
			(layer "F.SilkS")
			(hide yes)
			(effects
				(font
					(size 1.27 1.27)
				)
			)
		)
		(property "Value" "SCD01U16V1KX-GP"
			(at -2.831995 -1.740026 102)
			(unlocked yes)
			(layer "F.Fab")
			(hide yes)
			(effects
				(font
					(size 1.016 1.016)
					(thickness 0.1524)
				)
			)
		)
		(property "Device Type" "C0201H13"
			(at -2.831872 -3.264029 102)
			(unlocked yes)
			(layer "F.Fab")
			(hide yes)
			(effects
				(font
					(size 1.016 1.016)
					(thickness 0.1524)
				)
			)
		)
		(duplicate_pad_numbers_are_jumpers no)
		(fp_poly
			(pts
				(xy -0.279454 -0.647706) (xy 0.279346 -0.647706) (xy 0.279346 0.647694) (xy -0.279454 0.647694)
			)
			(stroke
				(width 0)
				(type default)
			)
			(fill no)
			(layer "F.CrtYd")
		)
		(fp_poly
			(pts
				(xy -0.279454 -0.647706) (xy 0.279346 -0.647706) (xy 0.279346 0.647694) (xy -0.279454 0.647694)
			)
			(stroke
				(width 0)
				(type default)
			)
			(fill no)
			(layer "F.Fab")
		)
		(pad "1" smd custom
			(at -0.000001 -0.2794 102)
			(size 0.0762 0.0762)
			(layers "F.Cu" "F.Mask" "F.Paste")
			(net "PHY_SCC_TO_IOC_41_DP")
			(options
				(clearance outline)
				(anchor circle)
			)
			(primitives
				(gr_poly
					(pts
						(arc
							(start 0.1524 -0.127)
							(mid 0.137521 -0.162921)
							(end 0.1016 -0.1778)
						)
						(arc
							(start -0.1016 -0.1778)
							(mid -0.137521 -0.162921)
							(end -0.1524 -0.127)
						)
						(arc
							(start -0.1524 0.127)
							(mid -0.137521 0.162921)
							(end -0.1016 0.1778)
						)
						(arc
							(start 0.1016 0.1778)
							(mid 0.137521 0.162921)
							(end 0.1524 0.127)
						)
					)
					(width 0)
					(fill yes)
				)
			)
		)
		(pad "2" smd custom
			(at 0.000001 0.2794 102)
			(size 0.0762 0.0762)
			(layers "F.Cu" "F.Mask" "F.Paste")
			(net "PHY_SCC_TO_IOC_C_41_DP")
			(options
				(clearance outline)
				(anchor circle)
			)
			(primitives
				(gr_poly
					(pts
						(arc
							(start 0.1524 -0.127)
							(mid 0.137521 -0.162921)
							(end 0.1016 -0.1778)
						)
						(arc
							(start -0.1016 -0.1778)
							(mid -0.137521 -0.162921)
							(end -0.1524 -0.127)
						)
						(arc
							(start -0.1524 0.127)
							(mid -0.137521 0.162921)
							(end -0.1016 0.1778)
						)
						(arc
							(start 0.1016 0.1778)
							(mid 0.137521 0.162921)
							(end 0.1524 0.127)
						)
					)
					(width 0)
					(fill yes)
				)
			)
		)
	)
)
